#ISCELL
  pure_quanta quanta_title_block_c *
  *
#ISCELL
  standard offpage *
  page114_i1
#ISCELL
  standard offpage *
  page114_i10
#ISCELL
  standard offpage *
  page114_i11
#ISCELL
  standard offpage *
  page114_i12
#ISCELL
  standard offpage *
  page114_i13
#ISCELL
  standard offpage *
  page114_i14
#ISCELL
  standard offpage *
  page114_i15
#ISCELL
  standard offpage *
  page114_i16
#CELL
  pure_quanta q_res *
  page114_i17
#CELL
  pure_quanta q_res *
  page114_i18
#CELL
  pure_quanta q_res *
  page114_i19
#ISCELL
  standard offpage *
  page114_i2
#CELL
  pure_quanta q_res *
  page114_i20
#CELL
  pure_quanta q_res *
  page114_i21
#CELL
  pure_quanta q_res *
  page114_i22
#CELL
  pure_quanta q_res *
  page114_i23
#CELL
  pure_quanta q_res *
  page114_i24
#CELL
  pure_quanta q_res *
  page114_i25
#CELL
  pure_quanta q_res *
  page114_i26
#CELL
  pure_quanta q_res *
  page114_i27
#CELL
  pure_quanta q_res *
  page114_i28
#CELL
  pure_quanta q_res *
  page114_i29
#ISCELL
  standard offpage *
  page114_i3
#CELL
  pure_quanta q_res *
  page114_i30
#CELL
  pure_quanta q_res *
  page114_i31
#CELL
  pure_quanta q_res *
  page114_i32
#ISCELL
  standard offpage *
  page114_i34
#ISCELL
  standard offpage *
  page114_i36
#ISCELL
  standard offpage *
  page114_i38
#ISCELL
  standard offpage *
  page114_i39
#ISCELL
  standard offpage *
  page114_i4
#ISCELL
  standard offpage *
  page114_i40
#ISCELL
  standard offpage *
  page114_i41
#ISCELL
  standard offpage *
  page114_i42
#ISCELL
  standard offpage *
  page114_i43
#ISCELL
  standard offpage *
  page114_i44
#ISCELL
  standard offpage *
  page114_i45
#ISCELL
  standard offpage *
  page114_i46
#ISCELL
  standard offpage *
  page114_i47
#ISCELL
  standard offpage *
  page114_i48
#ISCELL
  standard offpage *
  page114_i49
#ISCELL
  standard offpage *
  page114_i5
#ISCELL
  standard offpage *
  page114_i50
#ISCELL
  standard offpage *
  page114_i51
#ISCELL
  standard offpage *
  page114_i53
#ISCELL
  standard offpage *
  page114_i54
#ISCELL
  standard offpage *
  page114_i55
#ISCELL
  standard offpage *
  page114_i56
#CELL
  pure_quanta q_res *
  page114_i57
#CELL
  pure_quanta q_res *
  page114_i58
#CELL
  pure_quanta q_res *
  page114_i59
#ISCELL
  standard offpage *
  page114_i6
#CELL
  pure_quanta q_res *
  page114_i60
#CELL
  pure_quanta q_res *
  page114_i61
#CELL
  pure_quanta q_res *
  page114_i62
#CELL
  pure_quanta q_res *
  page114_i63
#CELL
  pure_quanta q_res *
  page114_i64
#CELL
  pure_quanta q_res *
  page114_i65
#CELL
  pure_quanta q_res *
  page114_i66
#CELL
  pure_quanta q_res *
  page114_i67
#CELL
  pure_quanta q_res *
  page114_i68
#CELL
  pure_quanta q_res *
  page114_i69
#ISCELL
  standard offpage *
  page114_i7
#ISCELL
  standard offpage *
  page114_i71
#ISCELL
  standard offpage *
  page114_i74
#ISCELL
  standard offpage *
  page114_i75
#CELL
  pure_quanta q_res *
  page114_i77
#CELL
  pure_quanta q_res *
  page114_i78
#CELL
  pure_quanta q_res *
  page114_i79
#ISCELL
  standard offpage *
  page114_i8
#ISCELL
  standard offpage *
  page114_i80
#ISCELL
  standard offpage *
  page114_i9
